(kicad_pcb
	(version 20240108)
	(generator "pcbnew")
	(generator_version "8.0")
	(general
		(thickness 1.6)
		(legacy_teardrops no)
	)
	(paper "A4")
	(title_block
		(title "Jetson Orin Baseboard OCuLink Expansion")
		(date "2025-03-18")
		(rev "1.1.0")
		(company "Antmicro Ltd")
		(comment 1 "www.antmicro.com")
		(comment 9 "footprints 78-81 of 119")
	)
	(layers
		(0 "F.Cu" signal)
		(1 "In1.Cu" signal)
		(2 "In2.Cu" signal)
		(31 "B.Cu" signal)
		(32 "B.Adhes" user "B.Adhesive")
		(33 "F.Adhes" user "F.Adhesive")
		(34 "B.Paste" user)
		(35 "F.Paste" user)
		(36 "B.SilkS" user "B.Silkscreen")
		(37 "F.SilkS" user "F.Silkscreen")
		(38 "B.Mask" user)
		(39 "F.Mask" user)
		(40 "Dwgs.User" user "User.Drawings")
		(41 "Cmts.User" user "User.Comments")
		(42 "Eco1.User" user "User.Eco1")
		(43 "Eco2.User" user "User.Eco2")
		(44 "Edge.Cuts" user)
		(45 "Margin" user)
		(46 "B.CrtYd" user "B.Courtyard")
		(47 "F.CrtYd" user "F.Courtyard")
		(48 "B.Fab" user)
		(49 "F.Fab" user)
	)
	(footprint "antmicro-footprints:C_0402_1005Metric"
		(layer "B.Cu")
		(at 128.005 116.687251 -90)
		(descr "Capacitor SMD 0402")
		(tags "capacitor SMD 0402")
		(property "Reference" "C8"
			(at 1.782749 -0.49 90)
			(layer "B.SilkS")
			(effects
				(font
					(size 0.7 0.7)
					(thickness 0.15)
				)
				(justify left bottom mirror)
			)
		)
		(property "Value" "C_100n_0402"
			(at -1.022927 -2.155213 90)
			(layer "B.Fab")
			(effects
				(font
					(size 0.7 0.7)
					(thickness 0.15)
				)
				(justify left bottom mirror)
			)
		)
		(property "Footprint" "antmicro-footprints:C_0402_1005Metric"
			(at 0 0 90)
			(layer "B.Fab")
			(hide yes)
			(effects
				(font
					(size 1.27 1.27)
					(thickness 0.15)
				)
				(justify mirror)
			)
		)
		(property "Datasheet" "https://www.murata.com/products/productdetail?partno=GRM155R61H104KE14%23"
			(at 0 0 90)
			(layer "B.Fab")
			(hide yes)
			(effects
				(font
					(size 1.27 1.27)
					(thickness 0.15)
				)
				(justify mirror)
			)
		)
		(property "Description" "SMD Multilayer Ceramic Capacitor, 0.1 µF, 50 V, 0402 [1005 Metric], ± 10%, X5R, GRM Series"
			(at 0 0 90)
			(layer "B.Fab")
			(hide yes)
			(effects
				(font
					(size 1.27 1.27)
					(thickness 0.15)
				)
				(justify mirror)
			)
		)
		(property "MPN" "GRM155R61H104KE14D"
			(at 0 0 90)
			(unlocked yes)
			(layer "B.Fab")
			(hide yes)
			(effects
				(font
					(size 1 1)
					(thickness 0.15)
				)
				(justify mirror)
			)
		)
		(property "Manufacturer" "Murata"
			(at 0 0 90)
			(unlocked yes)
			(layer "B.Fab")
			(hide yes)
			(effects
				(font
					(size 1 1)
					(thickness 0.15)
				)
				(justify mirror)
			)
		)
		(property "License" "Apache-2.0"
			(at 0 0 90)
			(unlocked yes)
			(layer "B.Fab")
			(hide yes)
			(effects
				(font
					(size 1 1)
					(thickness 0.15)
				)
				(justify mirror)
			)
		)
		(property "Author" "Antmicro"
			(at 0 0 90)
			(unlocked yes)
			(layer "B.Fab")
			(hide yes)
			(effects
				(font
					(size 1 1)
					(thickness 0.15)
				)
				(justify mirror)
			)
		)
		(property "Val" "100n"
			(at 0 0 90)
			(unlocked yes)
			(layer "B.Fab")
			(hide yes)
			(effects
				(font
					(size 1 1)
					(thickness 0.15)
				)
				(justify mirror)
			)
		)
		(property "Voltage" "50V"
			(at 0 0 90)
			(unlocked yes)
			(layer "B.Fab")
			(hide yes)
			(effects
				(font
					(size 1 1)
					(thickness 0.15)
				)
				(justify mirror)
			)
		)
		(property "Dielectric" "X5R"
			(at 0 0 90)
			(unlocked yes)
			(layer "B.Fab")
			(hide yes)
			(effects
				(font
					(size 1 1)
					(thickness 0.15)
				)
				(justify mirror)
			)
		)
		(property "Public" "False"
			(at 0 0 90)
			(unlocked yes)
			(layer "B.Fab")
			(hide yes)
			(effects
				(font
					(size 1 1)
					(thickness 0.15)
				)
				(justify mirror)
			)
		)
		(sheetname "Root")
		(sheetfile "jetson-orin-baseboard-oculink-expansion.kicad_sch")
		(attr smd)
		(fp_rect
			(start -0.925 0.47)
			(end 0.925 -0.47)
			(stroke
				(width 0.05)
				(type default)
			)
			(fill none)
			(layer "B.CrtYd")
		)
		(fp_line
			(start -0.494 0.25)
			(end -0.494 -0.248)
			(stroke
				(width 0.15)
				(type solid)
			)
			(layer "B.Fab")
		)
		(fp_line
			(start 0.504 0.25)
			(end -0.494 0.25)
			(stroke
				(width 0.15)
				(type solid)
			)
			(layer "B.Fab")
		)
		(fp_line
			(start -0.494 -0.248)
			(end 0.504 -0.248)
			(stroke
				(width 0.15)
				(type solid)
			)
			(layer "B.Fab")
		)
		(fp_line
			(start 0.504 -0.248)
			(end 0.504 0.25)
			(stroke
				(width 0.15)
				(type solid)
			)
			(layer "B.Fab")
		)
		(fp_text user "License: Apache-2.0"
			(at -0.939 -5.799 90)
			(layer "B.Fab")
			(hide yes)
			(effects
				(font
					(size 0.7 0.7)
					(thickness 0.15)
				)
				(justify left bottom mirror)
			)
		)
		(fp_text user "${REFERENCE}"
			(at -0.939 -4.599 90)
			(layer "B.Fab")
			(hide yes)
			(effects
				(font
					(size 0.7 0.7)
					(thickness 0.15)
				)
				(justify left bottom mirror)
			)
		)
		(fp_text user "Author: Antmicro"
			(at -0.939 -3.399 90)
			(layer "B.Fab")
			(hide yes)
			(effects
				(font
					(size 0.7 0.7)
					(thickness 0.15)
				)
				(justify left bottom mirror)
			)
		)
		(pad "1" smd roundrect
			(at -0.48 0 270)
			(size 0.59 0.64)
			(layers "B.Cu" "B.Paste" "B.Mask")
			(roundrect_rratio 0.25)
			(net 51 "GND")
			(pintype "passive")
		)
		(pad "2" smd roundrect
			(at 0.48 0 270)
			(size 0.59 0.64)
			(layers "B.Cu" "B.Paste" "B.Mask")
			(roundrect_rratio 0.25)
			(net 23 "+3V3")
			(pintype "passive")
		)
	)
	(footprint "antmicro-footprints:TP_SMD_1.5mm"
		(layer "B.Cu")
		(at 142.4 133.2 180)
		(property "Reference" "TP10"
			(at -0.8 -11.67964 0)
			(layer "B.SilkS")
			(hide yes)
			(effects
				(font
					(size 0.7 0.7)
					(thickness 0.15)
				)
				(justify left bottom mirror)
			)
		)
		(property "Value" "TP_1.5mm_SMD"
			(at 1.438222 -0.611409 0)
			(layer "B.Fab")
			(effects
				(font
					(size 0.7 0.7)
					(thickness 0.15)
				)
				(justify left bottom mirror)
			)
		)
		(property "Footprint" "antmicro-footprints:TP_SMD_1.5mm"
			(at 0 0 0)
			(layer "B.Fab")
			(hide yes)
			(effects
				(font
					(size 1.27 1.27)
					(thickness 0.15)
				)
				(justify mirror)
			)
		)
		(property "Description" "test point, SMT"
			(at 0 0 0)
			(layer "B.Fab")
			(hide yes)
			(effects
				(font
					(size 1.27 1.27)
					(thickness 0.15)
				)
				(justify mirror)
			)
		)
		(property "MPN" ""
			(at 0 0 0)
			(unlocked yes)
			(layer "B.Fab")
			(hide yes)
			(effects
				(font
					(size 1 1)
					(thickness 0.15)
				)
				(justify mirror)
			)
		)
		(property "Manufacturer" ""
			(at 0 0 0)
			(unlocked yes)
			(layer "B.Fab")
			(hide yes)
			(effects
				(font
					(size 1 1)
					(thickness 0.15)
				)
				(justify mirror)
			)
		)
		(property "Author" "Antmicro"
			(at 0 0 0)
			(unlocked yes)
			(layer "B.Fab")
			(hide yes)
			(effects
				(font
					(size 1 1)
					(thickness 0.15)
				)
				(justify mirror)
			)
		)
		(property "License" "Apache-2.0"
			(at 0 0 0)
			(unlocked yes)
			(layer "B.Fab")
			(hide yes)
			(effects
				(font
					(size 1 1)
					(thickness 0.15)
				)
				(justify mirror)
			)
		)
		(sheetname "Root")
		(sheetfile "jetson-orin-baseboard-oculink-expansion.kicad_sch")
		(attr exclude_from_pos_files exclude_from_bom)
		(fp_circle
			(center 0 0)
			(end 0.85 0)
			(stroke
				(width 0.05)
				(type default)
			)
			(fill none)
			(layer "B.CrtYd")
		)
		(fp_text user "Author: Antmicro"
			(at -0.7 -4.101 0)
			(layer "B.Fab")
			(hide yes)
			(effects
				(font
					(size 0.7 0.7)
					(thickness 0.15)
				)
				(justify left bottom mirror)
			)
		)
		(fp_text user "License: Apache-2.0"
			(at -0.7 -5.301 0)
			(layer "B.Fab")
			(hide yes)
			(effects
				(font
					(size 0.7 0.7)
					(thickness 0.15)
				)
				(justify left bottom mirror)
			)
		)
		(fp_text user "${REFERENCE}"
			(at -0.7 -2.9 0)
			(layer "B.Fab")
			(hide yes)
			(effects
				(font
					(size 0.7 0.7)
					(thickness 0.15)
				)
				(justify left bottom mirror)
			)
		)
		(pad "1" smd circle
			(at 0 0 270)
			(size 1.5 1.5)
			(layers "B.Cu" "B.Mask")
			(net 20 "+1V8")
			(pinfunction "1")
			(pintype "passive")
		)
	)
	(footprint "antmicro-footprints:C_0402_1005Metric"
		(layer "B.Cu")
		(at 122.775 125.795 90)
		(descr "Capacitor SMD 0402")
		(tags "capacitor SMD 0402")
		(property "Reference" "C20"
			(at 1.605 -0.365 90)
			(layer "B.SilkS")
			(effects
				(font
					(size 0.7 0.7)
					(thickness 0.15)
				)
				(justify right top mirror)
			)
		)
		(property "Value" "C_100n_0402"
			(at -1.022927 -2.155213 90)
			(layer "B.Fab")
			(effects
				(font
					(size 0.7 0.7)
					(thickness 0.15)
				)
				(justify right top mirror)
			)
		)
		(property "Footprint" "antmicro-footprints:C_0402_1005Metric"
			(at 0 0 90)
			(layer "B.Fab")
			(hide yes)
			(effects
				(font
					(size 1.27 1.27)
					(thickness 0.15)
				)
				(justify mirror)
			)
		)
		(property "Datasheet" "https://www.murata.com/products/productdetail?partno=GRM155R61H104KE14%23"
			(at 0 0 90)
			(layer "B.Fab")
			(hide yes)
			(effects
				(font
					(size 1.27 1.27)
					(thickness 0.15)
				)
				(justify mirror)
			)
		)
		(property "Description" "SMD Multilayer Ceramic Capacitor, 0.1 µF, 50 V, 0402 [1005 Metric], ± 10%, X5R, GRM Series"
			(at 0 0 90)
			(layer "B.Fab")
			(hide yes)
			(effects
				(font
					(size 1.27 1.27)
					(thickness 0.15)
				)
				(justify mirror)
			)
		)
		(property "MPN" "GRM155R61H104KE14D"
			(at 0 0 -90)
			(unlocked yes)
			(layer "B.Fab")
			(hide yes)
			(effects
				(font
					(size 1 1)
					(thickness 0.15)
				)
				(justify mirror)
			)
		)
		(property "Manufacturer" "Murata"
			(at 0 0 -90)
			(unlocked yes)
			(layer "B.Fab")
			(hide yes)
			(effects
				(font
					(size 1 1)
					(thickness 0.15)
				)
				(justify mirror)
			)
		)
		(property "License" "Apache-2.0"
			(at 0 0 -90)
			(unlocked yes)
			(layer "B.Fab")
			(hide yes)
			(effects
				(font
					(size 1 1)
					(thickness 0.15)
				)
				(justify mirror)
			)
		)
		(property "Author" "Antmicro"
			(at 0 0 -90)
			(unlocked yes)
			(layer "B.Fab")
			(hide yes)
			(effects
				(font
					(size 1 1)
					(thickness 0.15)
				)
				(justify mirror)
			)
		)
		(property "Val" "100n"
			(at 0 0 -90)
			(unlocked yes)
			(layer "B.Fab")
			(hide yes)
			(effects
				(font
					(size 1 1)
					(thickness 0.15)
				)
				(justify mirror)
			)
		)
		(property "Voltage" "50V"
			(at 0 0 -90)
			(unlocked yes)
			(layer "B.Fab")
			(hide yes)
			(effects
				(font
					(size 1 1)
					(thickness 0.15)
				)
				(justify mirror)
			)
		)
		(property "Dielectric" "X5R"
			(at 0 0 -90)
			(unlocked yes)
			(layer "B.Fab")
			(hide yes)
			(effects
				(font
					(size 1 1)
					(thickness 0.15)
				)
				(justify mirror)
			)
		)
		(property "Public" "False"
			(at 0 0 -90)
			(unlocked yes)
			(layer "B.Fab")
			(hide yes)
			(effects
				(font
					(size 1 1)
					(thickness 0.15)
				)
				(justify mirror)
			)
		)
		(sheetname "Root")
		(sheetfile "jetson-orin-baseboard-oculink-expansion.kicad_sch")
		(attr smd)
		(fp_rect
			(start -0.925 0.47)
			(end 0.925 -0.47)
			(stroke
				(width 0.05)
				(type default)
			)
			(fill none)
			(layer "B.CrtYd")
		)
		(fp_line
			(start 0.504 -0.248)
			(end 0.504 0.25)
			(stroke
				(width 0.15)
				(type solid)
			)
			(layer "B.Fab")
		)
		(fp_line
			(start -0.494 -0.248)
			(end 0.504 -0.248)
			(stroke
				(width 0.15)
				(type solid)
			)
			(layer "B.Fab")
		)
		(fp_line
			(start 0.504 0.25)
			(end -0.494 0.25)
			(stroke
				(width 0.15)
				(type solid)
			)
			(layer "B.Fab")
		)
		(fp_line
			(start -0.494 0.25)
			(end -0.494 -0.248)
			(stroke
				(width 0.15)
				(type solid)
			)
			(layer "B.Fab")
		)
		(fp_text user "Author: Antmicro"
			(at -0.939 -3.399 90)
			(layer "B.Fab")
			(hide yes)
			(effects
				(font
					(size 0.7 0.7)
					(thickness 0.15)
				)
				(justify right top mirror)
			)
		)
		(fp_text user "License: Apache-2.0"
			(at -0.939 -5.799 90)
			(layer "B.Fab")
			(hide yes)
			(effects
				(font
					(size 0.7 0.7)
					(thickness 0.15)
				)
				(justify right top mirror)
			)
		)
		(fp_text user "${REFERENCE}"
			(at -0.939 -4.599 90)
			(layer "B.Fab")
			(hide yes)
			(effects
				(font
					(size 0.7 0.7)
					(thickness 0.15)
				)
				(justify right top mirror)
			)
		)
		(pad "1" smd roundrect
			(at -0.48 0 90)
			(size 0.59 0.64)
			(layers "B.Cu" "B.Paste" "B.Mask")
			(roundrect_rratio 0.25)
			(net 51 "GND")
			(pintype "passive")
		)
		(pad "2" smd roundrect
			(at 0.48 0 90)
			(size 0.59 0.64)
			(layers "B.Cu" "B.Paste" "B.Mask")
			(roundrect_rratio 0.25)
			(net 23 "+3V3")
			(pintype "passive")
		)
	)
	(footprint "antmicro-footprints:R_0402_1005Metric"
		(layer "B.Cu")
		(at 127.944 128.00775)
		(descr "Resistor SMD 0402")
		(tags "resistor SMD 0402")
		(property "Reference" "R17"
			(at -3.274 -0.37775 0)
			(layer "B.SilkS")
			(effects
				(font
					(size 0.7 0.7)
					(thickness 0.15)
				)
				(justify right top mirror)
			)
		)
		(property "Value" "R_1k_0402"
			(at -1.011843 -1.772047 0)
			(layer "B.Fab")
			(effects
				(font
					(size 0.7 0.7)
					(thickness 0.15)
				)
				(justify right top mirror)
			)
		)
		(property "Footprint" "antmicro-footprints:R_0402_1005Metric"
			(at 0 0 0)
			(layer "B.Fab")
			(hide yes)
			(effects
				(font
					(size 1.27 1.27)
					(thickness 0.15)
				)
				(justify mirror)
			)
		)
		(property "Datasheet" "https://www.bourns.com/docs/product-datasheets/cr.pdf"
			(at 0 0 0)
			(layer "B.Fab")
			(hide yes)
			(effects
				(font
					(size 1.27 1.27)
					(thickness 0.15)
				)
				(justify mirror)
			)
		)
		(property "Description" "SMD Chip Resistor, 1 kohm, ± 1%, 63 mW, 0402 [1005 Metric], Thick Film, General Purpose"
			(at 0 0 0)
			(layer "B.Fab")
			(hide yes)
			(effects
				(font
					(size 1.27 1.27)
					(thickness 0.15)
				)
				(justify mirror)
			)
		)
		(property "MPN" "CR0402-FX-1001GLF"
			(at 0 0 180)
			(unlocked yes)
			(layer "B.Fab")
			(hide yes)
			(effects
				(font
					(size 1 1)
					(thickness 0.15)
				)
				(justify mirror)
			)
		)
		(property "Manufacturer" "Bourns"
			(at 0 0 180)
			(unlocked yes)
			(layer "B.Fab")
			(hide yes)
			(effects
				(font
					(size 1 1)
					(thickness 0.15)
				)
				(justify mirror)
			)
		)
		(property "License" "Apache-2.0"
			(at 0 0 180)
			(unlocked yes)
			(layer "B.Fab")
			(hide yes)
			(effects
				(font
					(size 1 1)
					(thickness 0.15)
				)
				(justify mirror)
			)
		)
		(property "Author" "Antmicro"
			(at 0 0 180)
			(unlocked yes)
			(layer "B.Fab")
			(hide yes)
			(effects
				(font
					(size 1 1)
					(thickness 0.15)
				)
				(justify mirror)
			)
		)
		(property "Val" "1k"
			(at 0 0 180)
			(unlocked yes)
			(layer "B.Fab")
			(hide yes)
			(effects
				(font
					(size 1 1)
					(thickness 0.15)
				)
				(justify mirror)
			)
		)
		(property "Tolerance" "1%"
			(at 0 0 180)
			(unlocked yes)
			(layer "B.Fab")
			(hide yes)
			(effects
				(font
					(size 1 1)
					(thickness 0.15)
				)
				(justify mirror)
			)
		)
		(property "Public" "False"
			(at 0 0 180)
			(unlocked yes)
			(layer "B.Fab")
			(hide yes)
			(effects
				(font
					(size 1 1)
					(thickness 0.15)
				)
				(justify mirror)
			)
		)
		(sheetname "Root")
		(sheetfile "jetson-orin-baseboard-oculink-expansion.kicad_sch")
		(attr smd dnp)
		(fp_rect
			(start -0.925 0.47)
			(end 0.925 -0.47)
			(stroke
				(width 0.05)
				(type default)
			)
			(fill none)
			(layer "B.CrtYd")
		)
		(fp_rect
			(start -0.5 0.25)
			(end 0.5 -0.25)
			(stroke
				(width 0.15)
				(type solid)
			)
			(fill none)
			(layer "B.Fab")
		)
		(fp_text user "${REFERENCE}"
			(at -0.95 -3.168 0)
			(layer "B.Fab")
			(hide yes)
			(effects
				(font
					(size 0.7 0.7)
					(thickness 0.15)
				)
				(justify right top mirror)
			)
		)
		(fp_text user "License: Apache-2.0"
			(at -0.95 -5.169 0)
			(layer "B.Fab")
			(hide yes)
			(effects
				(font
					(size 0.7 0.7)
					(thickness 0.15)
				)
				(justify right top mirror)
			)
		)
		(fp_text user "Author: Antmicro"
			(at -0.95 -4.169 0)
			(layer "B.Fab")
			(hide yes)
			(effects
				(font
					(size 0.7 0.7)
					(thickness 0.15)
				)
				(justify right top mirror)
			)
		)
		(pad "1" smd roundrect
			(at -0.48 0)
			(size 0.59 0.64)
			(layers "B.Cu" "B.Paste" "B.Mask")
			(roundrect_rratio 0.25)
			(net 23 "+3V3")
			(pintype "passive")
		)
		(pad "2" smd roundrect
			(at 0.48 0)
			(size 0.59 0.64)
			(layers "B.Cu" "B.Paste" "B.Mask")
			(roundrect_rratio 0.25)
			(net 96 "/TX_EQ0")
			(pintype "passive")
		)
	)
)
